(kicad_pcb
	(version 20260206)
	(generator "pcbnew")
	(generator_version "10.0")
	(general
		(thickness 1.6)
		(legacy_teardrops no)
	)
	(paper "A4")
	(title_block
		(title "ptb — Lightning_PTB_BRD.brd")
		(comment 1 "Lightning (Wiwynn / Facebook NVMe JBOF) / footprints 16-23 of 61")
	)
	(layers
		(0 "F.Cu" signal "TOP")
		(4 "In1.Cu" signal "L2GND")
		(6 "In2.Cu" signal "L3VCC")
		(2 "B.Cu" signal "BOTTOM")
		(9 "F.Adhes" user "F.Adhesive")
		(11 "B.Adhes" user "B.Adhesive")
		(13 "F.Paste" user "Package Geometry/Pastemask Top")
		(15 "B.Paste" user "Package Geometry/Pastemask Bottom")
		(5 "F.SilkS" user "Ref Des/Silkscreen Top")
		(7 "B.SilkS" user "Ref Des/Silkscreen Bottom")
		(1 "F.Mask" user "Board Geometry/Soldermask Top")
		(3 "B.Mask" user "Board Geometry/Soldermask Bottom")
		(17 "Dwgs.User" user "User.Drawings")
		(19 "Cmts.User" user "User.Comments")
		(21 "Eco1.User" user "User.Eco1")
		(23 "Eco2.User" user "User.Eco2")
		(25 "Edge.Cuts" user "Board Geometry/Outline")
		(27 "Margin" user)
		(31 "F.CrtYd" user "Package Geometry/Place Bound Top")
		(29 "B.CrtYd" user "Package Geometry/Place Bound Bottom")
		(35 "F.Fab" user "Ref Des/Assembly Top")
		(33 "B.Fab" user "Ref Des/Assembly Bottom")
	)
	(footprint ""
		(layer "F.Cu")
		(at 120.116092 -47.354744 180)
		(property "Reference" "C355"
			(at 0 0 180)
			(layer "F.SilkS")
			(hide yes)
			(effects
				(font
					(size 1.27 1.27)
				)
			)
		)
		(property "Value" "SC10U25V5KX-GP"
			(at -0.0762 -6.1214 180)
			(unlocked yes)
			(layer "F.Fab")
			(hide yes)
			(effects
				(font
					(size 1.016 1.016)
					(thickness 0.1524)
				)
			)
		)
		(property "Device Type" "C805H56"
			(at -0.0762 -8.1534 180)
			(unlocked yes)
			(layer "F.Fab")
			(hide yes)
			(effects
				(font
					(size 1.016 1.016)
					(thickness 0.1524)
				)
			)
		)
		(duplicate_pad_numbers_are_jumpers no)
		(fp_line
			(start 0.635 0)
			(end -0.635 0)
			(stroke
				(width 0.508)
				(type default)
			)
			(layer "F.SilkS")
		)
		(fp_rect
			(start -0.9652 1.778)
			(end 0.9652 -1.778)
			(stroke
				(width 0)
				(type default)
			)
			(fill no)
			(layer "F.CrtYd")
		)
		(fp_poly
			(pts
				(xy -0.9652 -1.778) (xy 0.9652 -1.778) (xy 0.9652 1.778) (xy -0.9652 1.778)
			)
			(stroke
				(width 0)
				(type default)
			)
			(fill no)
			(layer "F.Fab")
		)
		(pad "1" smd rect
			(at 0 -0.9652 180)
			(size 1.397 1.143)
			(layers "F.Cu" "F.Mask" "F.Paste")
			(net "P12V")
		)
		(pad "2" smd rect
			(at 0 0.9652 180)
			(size 1.397 1.143)
			(layers "F.Cu" "F.Mask" "F.Paste")
			(net "GND")
		)
	)
	(footprint ""
		(layer "F.Cu")
		(at 135.086344 -85.065108 -90)
		(property "Reference" "R366"
			(at 0 0 270)
			(layer "F.SilkS")
			(hide yes)
			(effects
				(font
					(size 1.27 1.27)
				)
			)
		)
		(property "Value" "0R2J-2-GP"
			(at 0.064008 -3.993896 270)
			(unlocked yes)
			(layer "F.Fab")
			(hide yes)
			(effects
				(font
					(size 1.016 1.016)
					(thickness 0.1524)
				)
			)
		)
		(property "Device Type" "R402H16"
			(at 0.064008 -5.517896 270)
			(unlocked yes)
			(layer "F.Fab")
			(hide yes)
			(effects
				(font
					(size 1.016 1.016)
					(thickness 0.1524)
				)
			)
		)
		(duplicate_pad_numbers_are_jumpers no)
		(fp_line
			(start -0.508 -0.9398)
			(end -0.508 0.9398)
			(stroke
				(width 0.1524)
				(type default)
			)
			(layer "F.SilkS")
		)
		(fp_line
			(start 0.508 -0.9398)
			(end -0.508 -0.9398)
			(stroke
				(width 0.1524)
				(type default)
			)
			(layer "F.SilkS")
		)
		(fp_rect
			(start -0.508 0.9398)
			(end 0.508 -0.9398)
			(stroke
				(width 0)
				(type default)
			)
			(fill no)
			(layer "F.CrtYd")
		)
		(fp_rect
			(start -0.508 0.9398)
			(end 0.508 -0.9398)
			(stroke
				(width 0)
				(type default)
			)
			(fill no)
			(layer "F.Fab")
		)
		(pad "1" smd custom
			(at 0 -0.4445 270)
			(size 0.1397 0.1397)
			(layers "F.Cu" "F.Mask" "F.Paste")
			(net "IR_SWITCH_E")
			(options
				(clearance outline)
				(anchor circle)
			)
			(primitives
				(gr_poly
					(pts
						(arc
							(start -0.1778 -0.2794)
							(mid -0.249642 -0.249642)
							(end -0.2794 -0.1778)
						)
						(arc
							(start -0.2794 0.1778)
							(mid -0.249642 0.249642)
							(end -0.1778 0.2794)
						)
						(arc
							(start 0.1778 0.2794)
							(mid 0.249642 0.249642)
							(end 0.2794 0.1778)
						)
						(arc
							(start 0.2794 -0.1778)
							(mid 0.249642 -0.249642)
							(end 0.1778 -0.2794)
						)
					)
					(width 0)
					(fill yes)
				)
			)
		)
		(pad "2" smd custom
			(at 0 0.4445 270)
			(size 0.1397 0.1397)
			(layers "F.Cu" "F.Mask" "F.Paste")
			(net "TRAY PRESENT_OUT_NET")
			(options
				(clearance outline)
				(anchor circle)
			)
			(primitives
				(gr_poly
					(pts
						(arc
							(start -0.1778 -0.2794)
							(mid -0.249642 -0.249642)
							(end -0.2794 -0.1778)
						)
						(arc
							(start -0.2794 0.1778)
							(mid -0.249642 0.249642)
							(end -0.1778 0.2794)
						)
						(arc
							(start 0.1778 0.2794)
							(mid 0.249642 0.249642)
							(end 0.2794 0.1778)
						)
						(arc
							(start 0.2794 -0.1778)
							(mid 0.249642 -0.249642)
							(end 0.1778 -0.2794)
						)
					)
					(width 0)
					(fill yes)
				)
			)
		)
	)
	(footprint ""
		(layer "F.Cu")
		(at 7.659878 -15.499842)
		(property "Reference" "H3"
			(at 0 0 0)
			(layer "F.SilkS")
			(hide yes)
			(effects
				(font
					(size 1.27 1.27)
				)
			)
		)
		(property "Value" "HOLE"
			(at -8.9789 -1.1176 0)
			(unlocked yes)
			(layer "F.Fab")
			(hide yes)
			(effects
				(font
					(size 1.016 1.016)
					(thickness 0.1524)
				)
			)
		)
		(property "Device Type" "HTE9B9R355-R-766"
			(at -8.9789 -2.6416 0)
			(unlocked yes)
			(layer "F.Fab")
			(hide yes)
			(effects
				(font
					(size 1.016 1.016)
					(thickness 0.1524)
				)
			)
		)
		(duplicate_pad_numbers_are_jumpers no)
		(fp_poly
			(pts
				(arc
					(start 4.8133 0)
					(mid -4.8133 0)
					(end 4.8133 0)
				)
			)
			(stroke
				(width 0)
				(type default)
			)
			(fill no)
			(layer "B.CrtYd")
		)
		(fp_poly
			(pts
				(arc
					(start 0 -4.8133)
					(mid 4.8133 0)
					(end 0 4.8133)
				)
				(xy -7.9629 4.8133) (xy -7.9629 -4.8133)
			)
			(stroke
				(width 0)
				(type default)
			)
			(fill no)
			(layer "F.CrtYd")
		)
		(fp_poly
			(pts
				(arc
					(start 4.8133 0)
					(mid -4.8133 0)
					(end 4.8133 0)
				)
			)
			(stroke
				(width 0)
				(type default)
			)
			(fill no)
			(layer "B.Fab")
		)
		(fp_poly
			(pts
				(arc
					(start 0 -4.8133)
					(mid 4.8133 0)
					(end 0 4.8133)
				)
				(xy -7.9629 4.8133) (xy -7.9629 -4.8133)
			)
			(stroke
				(width 0)
				(type default)
			)
			(fill no)
			(layer "F.Fab")
		)
		(pad "1" thru_hole custom
			(at 0 0)
			(size 2.25425 2.25425)
			(drill 3.556)
			(layers "*.Cu" "*.Mask")
			(remove_unused_layers no)
			(net "GND")
			(clearance -3.7973)
			(thermal_gap 0.3048)
			(options
				(clearance outline)
				(anchor circle)
			)
			(primitives
				(gr_poly
					(pts
						(arc
							(start 1.5748 -4.5085)
							(mid 6.0833 0)
							(end 1.5748 4.5085)
						)
						(xy -6.0833 4.5085) (xy -6.0833 -4.5085)
					)
					(width 0)
					(fill yes)
				)
			)
			(padstack
				(mode front_inner_back)
				(layer "Inner"
					(shape circle)
					(size 3.9624 3.9624)
					(clearance 0.3048)
				)
				(layer "B.Cu"
					(shape circle)
					(size 9.017 9.017)
					(clearance -2.2225)
				)
			)
		)
	)
	(footprint ""
		(layer "F.Cu")
		(at 133.223 -82.804 90)
		(property "Reference" "R376"
			(at 0 0 90)
			(layer "F.SilkS")
			(hide yes)
			(effects
				(font
					(size 1.27 1.27)
				)
			)
		)
		(property "Value" "100KR2F-L1-GP"
			(at 0.064008 -3.993896 90)
			(unlocked yes)
			(layer "F.Fab")
			(hide yes)
			(effects
				(font
					(size 1.016 1.016)
					(thickness 0.1524)
				)
			)
		)
		(property "Device Type" "R402H16"
			(at 0.064008 -5.517896 90)
			(unlocked yes)
			(layer "F.Fab")
			(hide yes)
			(effects
				(font
					(size 1.016 1.016)
					(thickness 0.1524)
				)
			)
		)
		(duplicate_pad_numbers_are_jumpers no)
		(fp_line
			(start 0.508 -0.9398)
			(end -0.508 -0.9398)
			(stroke
				(width 0.1524)
				(type default)
			)
			(layer "F.SilkS")
		)
		(fp_line
			(start -0.508 -0.9398)
			(end -0.508 0.9398)
			(stroke
				(width 0.1524)
				(type default)
			)
			(layer "F.SilkS")
		)
		(fp_rect
			(start -0.508 0.9398)
			(end 0.508 -0.9398)
			(stroke
				(width 0)
				(type default)
			)
			(fill no)
			(layer "F.CrtYd")
		)
		(fp_rect
			(start -0.508 0.9398)
			(end 0.508 -0.9398)
			(stroke
				(width 0)
				(type default)
			)
			(fill no)
			(layer "F.Fab")
		)
		(pad "1" smd custom
			(at 0 -0.4445 90)
			(size 0.1397 0.1397)
			(layers "F.Cu" "F.Mask" "F.Paste")
			(net "P3V3")
			(options
				(clearance outline)
				(anchor circle)
			)
			(primitives
				(gr_poly
					(pts
						(arc
							(start -0.1778 -0.2794)
							(mid -0.249642 -0.249642)
							(end -0.2794 -0.1778)
						)
						(arc
							(start -0.2794 0.1778)
							(mid -0.249642 0.249642)
							(end -0.1778 0.2794)
						)
						(arc
							(start 0.1778 0.2794)
							(mid 0.249642 0.249642)
							(end 0.2794 0.1778)
						)
						(arc
							(start 0.2794 -0.1778)
							(mid 0.249642 -0.249642)
							(end 0.1778 -0.2794)
						)
					)
					(width 0)
					(fill yes)
				)
			)
		)
		(pad "2" smd custom
			(at 0 0.4445 90)
			(size 0.1397 0.1397)
			(layers "F.Cu" "F.Mask" "F.Paste")
			(net "TRAY PRESENT_OUT#_C")
			(options
				(clearance outline)
				(anchor circle)
			)
			(primitives
				(gr_poly
					(pts
						(arc
							(start -0.1778 -0.2794)
							(mid -0.249642 -0.249642)
							(end -0.2794 -0.1778)
						)
						(arc
							(start -0.2794 0.1778)
							(mid -0.249642 0.249642)
							(end -0.1778 0.2794)
						)
						(arc
							(start 0.1778 0.2794)
							(mid 0.249642 0.249642)
							(end 0.2794 0.1778)
						)
						(arc
							(start 0.2794 -0.1778)
							(mid 0.249642 -0.249642)
							(end 0.1778 -0.2794)
						)
					)
					(width 0)
					(fill yes)
				)
			)
		)
	)
	(footprint ""
		(layer "F.Cu")
		(at 113.919 -47.371 180)
		(property "Reference" "C362"
			(at 0 0 180)
			(layer "F.SilkS")
			(hide yes)
			(effects
				(font
					(size 1.27 1.27)
				)
			)
		)
		(property "Value" "SC47U16V0MX-GP"
			(at -0.00254 -4.78536 180)
			(unlocked yes)
			(layer "F.Fab")
			(hide yes)
			(effects
				(font
					(size 1.016 1.016)
					(thickness 0.1524)
				)
			)
		)
		(property "Device Type" "C1210H107"
			(at -0.00254 -6.38048 180)
			(unlocked yes)
			(layer "F.Fab")
			(hide yes)
			(effects
				(font
					(size 1.016 1.016)
					(thickness 0.1524)
				)
			)
		)
		(duplicate_pad_numbers_are_jumpers no)
		(fp_line
			(start 1.5748 2.3368)
			(end 1.5748 0.762)
			(stroke
				(width 0.1524)
				(type default)
			)
			(layer "F.SilkS")
		)
		(fp_line
			(start 1.5748 -0.762)
			(end 1.5748 -2.3368)
			(stroke
				(width 0.1524)
				(type default)
			)
			(layer "F.SilkS")
		)
		(fp_line
			(start 1.5748 -2.3368)
			(end -1.5748 -2.3368)
			(stroke
				(width 0.1524)
				(type default)
			)
			(layer "F.SilkS")
		)
		(fp_line
			(start -1.5748 2.3368)
			(end 1.5748 2.3368)
			(stroke
				(width 0.1524)
				(type default)
			)
			(layer "F.SilkS")
		)
		(fp_line
			(start -1.5748 0.762)
			(end -1.5748 2.3368)
			(stroke
				(width 0.1524)
				(type default)
			)
			(layer "F.SilkS")
		)
		(fp_line
			(start -1.5748 -2.3368)
			(end -1.5748 -0.762)
			(stroke
				(width 0.1524)
				(type default)
			)
			(layer "F.SilkS")
		)
		(fp_rect
			(start -1.651 2.413)
			(end 1.651 -2.413)
			(stroke
				(width 0)
				(type default)
			)
			(fill no)
			(layer "F.CrtYd")
		)
		(fp_poly
			(pts
				(xy 1.651 2.413) (xy 1.651 -2.413) (xy -1.651 -2.413) (xy -1.651 2.413)
			)
			(stroke
				(width 0)
				(type default)
			)
			(fill no)
			(layer "F.Fab")
		)
		(pad "1" smd rect
			(at 0 -1.4732 180)
			(size 2.794 1.397)
			(layers "F.Cu" "F.Mask" "F.Paste")
			(net "P12V")
		)
		(pad "2" smd rect
			(at 0 1.4732 180)
			(size 2.794 1.397)
			(layers "F.Cu" "F.Mask" "F.Paste")
			(net "GND")
		)
	)
	(footprint ""
		(layer "F.Cu")
		(at 9.684512 -95.791528 180)
		(property "Reference" "C357"
			(at 0 0 180)
			(layer "F.SilkS")
			(hide yes)
			(effects
				(font
					(size 1.27 1.27)
				)
			)
		)
		(property "Value" "SC220P50V3JN-GP"
			(at 0 -2.8194 180)
			(unlocked yes)
			(layer "F.Fab")
			(hide yes)
			(effects
				(font
					(size 1.016 1.016)
					(thickness 0.1524)
				)
			)
		)
		(property "Device Type" "C603H36"
			(at 0 -4.3434 180)
			(unlocked yes)
			(layer "F.Fab")
			(hide yes)
			(effects
				(font
					(size 1.016 1.016)
					(thickness 0.1524)
				)
			)
		)
		(duplicate_pad_numbers_are_jumpers no)
		(fp_line
			(start 0.508 0)
			(end -0.508 0)
			(stroke
				(width 0.2032)
				(type default)
			)
			(layer "F.SilkS")
		)
		(fp_rect
			(start -0.5842 1.3335)
			(end 0.5842 -1.3335)
			(stroke
				(width 0)
				(type default)
			)
			(fill no)
			(layer "F.CrtYd")
		)
		(fp_rect
			(start -0.5842 1.3335)
			(end 0.5842 -1.3335)
			(stroke
				(width 0)
				(type default)
			)
			(fill no)
			(layer "F.Fab")
		)
		(pad "1" smd custom
			(at 0 -0.762 180)
			(size 0.2159 0.2159)
			(layers "F.Cu" "F.Mask" "F.Paste")
			(net "I2C_C_SDA")
			(options
				(clearance outline)
				(anchor circle)
			)
			(primitives
				(gr_poly
					(pts
						(arc
							(start -0.3302 -0.4318)
							(mid -0.402042 -0.402042)
							(end -0.4318 -0.3302)
						)
						(arc
							(start -0.4318 0.3302)
							(mid -0.402042 0.402042)
							(end -0.3302 0.4318)
						)
						(arc
							(start 0.3302 0.4318)
							(mid 0.402042 0.402042)
							(end 0.4318 0.3302)
						)
						(arc
							(start 0.4318 -0.3302)
							(mid 0.402042 -0.402042)
							(end 0.3302 -0.4318)
						)
					)
					(width 0)
					(fill yes)
				)
			)
		)
		(pad "2" smd custom
			(at 0 0.762 180)
			(size 0.2159 0.2159)
			(layers "F.Cu" "F.Mask" "F.Paste")
			(net "GND")
			(options
				(clearance outline)
				(anchor circle)
			)
			(primitives
				(gr_poly
					(pts
						(arc
							(start -0.3302 -0.4318)
							(mid -0.402042 -0.402042)
							(end -0.4318 -0.3302)
						)
						(arc
							(start -0.4318 0.3302)
							(mid -0.402042 0.402042)
							(end -0.3302 0.4318)
						)
						(arc
							(start 0.3302 0.4318)
							(mid 0.402042 0.402042)
							(end 0.4318 0.3302)
						)
						(arc
							(start 0.4318 -0.3302)
							(mid 0.402042 -0.402042)
							(end 0.3302 -0.4318)
						)
					)
					(width 0)
					(fill yes)
				)
			)
		)
	)
	(footprint ""
		(layer "F.Cu")
		(at 156.972 -18.923)
		(property "Reference" "R483"
			(at 0 0 0)
			(layer "F.SilkS")
			(hide yes)
			(effects
				(font
					(size 1.27 1.27)
				)
			)
		)
		(property "Value" "2KR3F-L-GP"
			(at -0.0254 -2.5146 0)
			(unlocked yes)
			(layer "F.Fab")
			(hide yes)
			(effects
				(font
					(size 1.016 1.016)
					(thickness 0.1524)
				)
			)
		)
		(property "Device Type" "R603H22"
			(at -0.0254 -4.0386 0)
			(unlocked yes)
			(layer "F.Fab")
			(hide yes)
			(effects
				(font
					(size 1.016 1.016)
					(thickness 0.1524)
				)
			)
		)
		(duplicate_pad_numbers_are_jumpers no)
		(fp_line
			(start -0.4826 0)
			(end -0.2032 0)
			(stroke
				(width 0.2032)
				(type default)
			)
			(layer "F.SilkS")
		)
		(fp_line
			(start 0.2032 0)
			(end 0.4826 0)
			(stroke
				(width 0.2032)
				(type default)
			)
			(layer "F.SilkS")
		)
		(fp_rect
			(start -0.5842 1.3335)
			(end 0.5842 -1.3335)
			(stroke
				(width 0)
				(type default)
			)
			(fill no)
			(layer "F.CrtYd")
		)
		(fp_rect
			(start -0.5842 1.3335)
			(end 0.5842 -1.3335)
			(stroke
				(width 0)
				(type default)
			)
			(fill no)
			(layer "F.Fab")
		)
		(pad "1" smd custom
			(at 0 -0.762)
			(size 0.2159 0.2159)
			(layers "F.Cu" "F.Mask" "F.Paste")
			(net "P12V")
			(options
				(clearance outline)
				(anchor circle)
			)
			(primitives
				(gr_poly
					(pts
						(arc
							(start -0.3302 -0.4318)
							(mid -0.402042 -0.402042)
							(end -0.4318 -0.3302)
						)
						(arc
							(start -0.4318 0.3302)
							(mid -0.402042 0.402042)
							(end -0.3302 0.4318)
						)
						(arc
							(start 0.3302 0.4318)
							(mid 0.402042 0.402042)
							(end 0.4318 0.3302)
						)
						(arc
							(start 0.4318 -0.3302)
							(mid 0.402042 -0.402042)
							(end 0.3302 -0.4318)
						)
					)
					(width 0)
					(fill yes)
				)
			)
		)
		(pad "2" smd custom
			(at 0 0.762)
			(size 0.2159 0.2159)
			(layers "F.Cu" "F.Mask" "F.Paste")
			(net "TPS2490_LED")
			(options
				(clearance outline)
				(anchor circle)
			)
			(primitives
				(gr_poly
					(pts
						(arc
							(start -0.3302 -0.4318)
							(mid -0.402042 -0.402042)
							(end -0.4318 -0.3302)
						)
						(arc
							(start -0.4318 0.3302)
							(mid -0.402042 0.402042)
							(end -0.3302 0.4318)
						)
						(arc
							(start 0.3302 0.4318)
							(mid 0.402042 0.402042)
							(end 0.4318 0.3302)
						)
						(arc
							(start 0.4318 -0.3302)
							(mid 0.402042 -0.402042)
							(end 0.3302 -0.4318)
						)
					)
					(width 0)
					(fill yes)
				)
			)
		)
	)
	(footprint ""
		(layer "F.Cu")
		(at 0.050038 -49.179226 180)
		(property "Reference" "C348"
			(at 0 0 180)
			(layer "F.SilkS")
			(hide yes)
			(effects
				(font
					(size 1.27 1.27)
				)
			)
		)
		(property "Value" "SC10U25V5KX-GP"
			(at -0.0762 -6.1214 180)
			(unlocked yes)
			(layer "F.Fab")
			(hide yes)
			(effects
				(font
					(size 1.016 1.016)
					(thickness 0.1524)
				)
			)
		)
		(property "Device Type" "C805H56"
			(at -0.0762 -8.1534 180)
			(unlocked yes)
			(layer "F.Fab")
			(hide yes)
			(effects
				(font
					(size 1.016 1.016)
					(thickness 0.1524)
				)
			)
		)
		(duplicate_pad_numbers_are_jumpers no)
		(fp_line
			(start 0.635 0)
			(end -0.635 0)
			(stroke
				(width 0.508)
				(type default)
			)
			(layer "F.SilkS")
		)
		(fp_rect
			(start -0.9652 1.778)
			(end 0.9652 -1.778)
			(stroke
				(width 0)
				(type default)
			)
			(fill no)
			(layer "F.CrtYd")
		)
		(fp_poly
			(pts
				(xy -0.9652 -1.778) (xy 0.9652 -1.778) (xy 0.9652 1.778) (xy -0.9652 1.778)
			)
			(stroke
				(width 0)
				(type default)
			)
			(fill no)
			(layer "F.Fab")
		)
		(pad "1" smd rect
			(at 0 -0.9652 180)
			(size 1.397 1.143)
			(layers "F.Cu" "F.Mask" "F.Paste")
			(net "P12V")
		)
		(pad "2" smd rect
			(at 0 0.9652 180)
			(size 1.397 1.143)
			(layers "F.Cu" "F.Mask" "F.Paste")
			(net "GND")
		)
	)
)
